# BASEBOARD_FAB2 (Tioga Pass) — schematic netlist excerpt (pin names and nets, part order shuffled) for the footprints in the layout excerpt that follows; sources: Cadence DE-HDL packaged netlist, KiCad conversion of Wiwynn_Tioga_Pass_MB.brd

R6T1  RES  240 1.0% CHIP  pkg 0402  page 99 : A = PVCCIO_CPU1 ; B = SMB_DDR_GHJ_SDA_G
C1M37  CAP_A  1.0UF 6.3V 10% X6S  pkg 0402V  page 112 : A = P3V3_STBY ; B = GND
R2R2  RES  33.2 1% CHIP  pkg 0402  page 190 : A = RST_RSMRST_R_N ; B = RST_RSMRST_N

(kicad_pcb
	(version 20260206)
	(generator "pcbnew")
	(generator_version "10.0")
	(general
		(thickness 1.6)
		(legacy_teardrops no)
	)
	(paper "A4")
	(title_block
		(title "Wiwynn_Tioga_Pass_MB.brd")
		(comment 1 "Tioga Pass / footprints 3197-3199 of 4770")
	)
	(layers
		(0 "F.Cu" signal "TOP")
		(4 "In1.Cu" signal "L2GND")
		(6 "In2.Cu" signal "L3")
		(8 "In3.Cu" signal "L4GND")
		(10 "In4.Cu" signal "L5")
		(12 "In5.Cu" signal "L6GND")
		(14 "In6.Cu" signal "L7VCC")
		(16 "In7.Cu" signal "L8VCC")
		(18 "In8.Cu" signal "L9GND")
		(20 "In9.Cu" signal "L10")
		(22 "In10.Cu" signal "L11GND")
		(24 "In11.Cu" signal "L12")
		(26 "In12.Cu" signal "L13GND")
		(2 "B.Cu" signal "BOTTOM")
		(9 "F.Adhes" user "F.Adhesive")
		(11 "B.Adhes" user "B.Adhesive")
		(13 "F.Paste" user "Package Geometry/Pastemask Top")
		(15 "B.Paste" user "Package Geometry/Pastemask Bottom")
		(5 "F.SilkS" user "Ref Des/Silkscreen Top")
		(7 "B.SilkS" user "Ref Des/Silkscreen Bottom")
		(1 "F.Mask" user "Board Geometry/Soldermask Top")
		(3 "B.Mask" user "Board Geometry/Soldermask Bottom")
		(17 "Dwgs.User" user "User.Drawings")
		(19 "Cmts.User" user "User.Comments")
		(21 "Eco1.User" user "User.Eco1")
		(23 "Eco2.User" user "User.Eco2")
		(25 "Edge.Cuts" user "Board Geometry/Outline")
		(27 "Margin" user)
		(31 "F.CrtYd" user "Package Geometry/Place Bound Top")
		(29 "B.CrtYd" user "Package Geometry/Place Bound Bottom")
		(35 "F.Fab" user "Ref Des/Assembly Top")
		(33 "B.Fab" user "Ref Des/Assembly Bottom")
	)
	(footprint ""
		(layer "B.Cu")
		(at 378.53874 -67.21856)
		(property "Reference" "R2R2"
			(at 0 0 0)
			(layer "B.SilkS")
			(hide yes)
			(effects
				(font
					(size 1.27 1.27)
				)
				(justify mirror)
			)
		)
		(property "Value" ""
			(at 0 0 0)
			(layer "B.Fab")
			(effects
				(font
					(size 1.27 1.27)
				)
				(justify mirror)
			)
		)
		(duplicate_pad_numbers_are_jumpers no)
		(fp_poly
			(pts
				(xy 0.2794 -0.1016) (xy -0.2794 -0.1016) (xy -0.2794 0.9906) (xy 0.2794 0.9906)
			)
			(stroke
				(width 0)
				(type default)
			)
			(fill no)
			(layer "B.CrtYd")
		)
		(fp_line
			(start -0.2794 -0.1016)
			(end 0.2794 -0.1016)
			(stroke
				(width 0.1)
				(type default)
			)
			(layer "B.Fab")
		)
		(fp_line
			(start -0.2794 0.9906)
			(end -0.2794 -0.1016)
			(stroke
				(width 0.1)
				(type default)
			)
			(layer "B.Fab")
		)
		(fp_line
			(start 0.2794 -0.1016)
			(end 0.2794 0.9906)
			(stroke
				(width 0.1)
				(type default)
			)
			(layer "B.Fab")
		)
		(fp_line
			(start 0.2794 0.9906)
			(end -0.2794 0.9906)
			(stroke
				(width 0.1)
				(type default)
			)
			(layer "B.Fab")
		)
		(pad "1" smd rect
			(at 0 0 180)
			(size 0.508 0.508)
			(layers "B.Cu" "B.Mask" "B.Paste")
			(net "RST_RSMRST_R_N")
		)
		(pad "2" smd rect
			(at 0 0.889 180)
			(size 0.508 0.508)
			(layers "B.Cu" "B.Mask" "B.Paste")
			(net "RST_RSMRST_N")
		)
		(zone
			(layer "B.Cu")
			(hatch none 0.5)
			(connect_pads
				(clearance 0)
			)
			(min_thickness 0.25)
			(keepout
				(tracks allowed)
				(vias not_allowed)
				(pads allowed)
				(copperpour not_allowed)
				(footprints allowed)
			)
			(placement
				(enabled no)
				(sheetname "")
			)
			(fill
				(thermal_gap 0.5)
				(thermal_bridge_width 0.5)
				(island_removal_mode 0)
			)
			(polygon
				(pts
					(xy 378.79274 -66.96456) (xy 378.28474 -66.96456) (xy 378.28474 -66.58356) (xy 378.79274 -66.58356)
				)
			)
		)
		(zone
			(layer "B.Cu")
			(hatch none 0.5)
			(connect_pads
				(clearance 0)
			)
			(min_thickness 0.25)
			(keepout
				(tracks not_allowed)
				(vias allowed)
				(pads allowed)
				(copperpour not_allowed)
				(footprints allowed)
			)
			(placement
				(enabled no)
				(sheetname "")
			)
			(fill
				(thermal_gap 0.5)
				(thermal_bridge_width 0.5)
				(island_removal_mode 0)
			)
			(polygon
				(pts
					(xy 378.79274 -66.58356) (xy 378.28474 -66.58356) (xy 378.28474 -66.96456) (xy 378.79274 -66.96456)
				)
			)
		)
	)
	(footprint ""
		(layer "B.Cu")
		(at 169.770552 -23.562564 -90)
		(property "Reference" "R6T1"
			(at 0 0 90)
			(layer "B.SilkS")
			(hide yes)
			(effects
				(font
					(size 1.27 1.27)
				)
				(justify mirror)
			)
		)
		(property "Value" ""
			(at 0 0 90)
			(layer "B.Fab")
			(effects
				(font
					(size 1.27 1.27)
				)
				(justify mirror)
			)
		)
		(duplicate_pad_numbers_are_jumpers no)
		(fp_poly
			(pts
				(xy 0.2794 -0.1016) (xy -0.2794 -0.1016) (xy -0.2794 0.9906) (xy 0.2794 0.9906)
			)
			(stroke
				(width 0)
				(type default)
			)
			(fill no)
			(layer "B.CrtYd")
		)
		(fp_line
			(start -0.2794 0.9906)
			(end -0.2794 -0.1016)
			(stroke
				(width 0.1)
				(type default)
			)
			(layer "B.Fab")
		)
		(fp_line
			(start 0.2794 0.9906)
			(end -0.2794 0.9906)
			(stroke
				(width 0.1)
				(type default)
			)
			(layer "B.Fab")
		)
		(fp_line
			(start -0.2794 -0.1016)
			(end 0.2794 -0.1016)
			(stroke
				(width 0.1)
				(type default)
			)
			(layer "B.Fab")
		)
		(fp_line
			(start 0.2794 -0.1016)
			(end 0.2794 0.9906)
			(stroke
				(width 0.1)
				(type default)
			)
			(layer "B.Fab")
		)
		(pad "1" smd rect
			(at 0 0 90)
			(size 0.508 0.508)
			(layers "B.Cu" "B.Mask" "B.Paste")
			(net "PVCCIO_CPU1")
		)
		(pad "2" smd rect
			(at 0 0.889 90)
			(size 0.508 0.508)
			(layers "B.Cu" "B.Mask" "B.Paste")
			(net "SMB_DDR_GHJ_SDA_G")
		)
		(zone
			(layer "B.Cu")
			(hatch none 0.5)
			(connect_pads
				(clearance 0)
			)
			(min_thickness 0.25)
			(keepout
				(tracks not_allowed)
				(vias allowed)
				(pads allowed)
				(copperpour not_allowed)
				(footprints allowed)
			)
			(placement
				(enabled no)
				(sheetname "")
			)
			(fill
				(thermal_gap 0.5)
				(thermal_bridge_width 0.5)
				(island_removal_mode 0)
			)
			(polygon
				(pts
					(xy 169.135552 -23.308564) (xy 169.135552 -23.816564) (xy 169.516552 -23.816564) (xy 169.516552 -23.308564)
				)
			)
		)
		(zone
			(layer "B.Cu")
			(hatch none 0.5)
			(connect_pads
				(clearance 0)
			)
			(min_thickness 0.25)
			(keepout
				(tracks allowed)
				(vias not_allowed)
				(pads allowed)
				(copperpour not_allowed)
				(footprints allowed)
			)
			(placement
				(enabled no)
				(sheetname "")
			)
			(fill
				(thermal_gap 0.5)
				(thermal_bridge_width 0.5)
				(island_removal_mode 0)
			)
			(polygon
				(pts
					(xy 169.516552 -23.308564) (xy 169.516552 -23.816564) (xy 169.135552 -23.816564) (xy 169.135552 -23.308564)
				)
			)
		)
	)
	(footprint ""
		(layer "B.Cu")
		(at 460.8576 -126.7714)
		(property "Reference" "C1M37"
			(at 0 0 0)
			(layer "B.SilkS")
			(hide yes)
			(effects
				(font
					(size 1.27 1.27)
				)
				(justify mirror)
			)
		)
		(property "Value" ""
			(at 0 0 0)
			(layer "B.Fab")
			(effects
				(font
					(size 1.27 1.27)
				)
				(justify mirror)
			)
		)
		(duplicate_pad_numbers_are_jumpers no)
		(fp_poly
			(pts
				(xy -0.3048 -0.1016) (xy -0.3048 0.9906) (xy 0.3048 0.9906) (xy 0.3048 -0.1016)
			)
			(stroke
				(width 0)
				(type default)
			)
			(fill no)
			(layer "B.CrtYd")
		)
		(fp_line
			(start -0.3048 -0.1016)
			(end 0.3048 -0.1016)
			(stroke
				(width 0.1)
				(type default)
			)
			(layer "B.Fab")
		)
		(fp_line
			(start -0.3048 0.9906)
			(end -0.3048 -0.1016)
			(stroke
				(width 0.1)
				(type default)
			)
			(layer "B.Fab")
		)
		(fp_line
			(start 0.3048 -0.1016)
			(end 0.3048 0.9906)
			(stroke
				(width 0.1)
				(type default)
			)
			(layer "B.Fab")
		)
		(fp_line
			(start 0.3048 0.9906)
			(end -0.3048 0.9906)
			(stroke
				(width 0.1)
				(type default)
			)
			(layer "B.Fab")
		)
		(pad "1" smd rect
			(at 0 0 180)
			(size 0.508 0.508)
			(layers "B.Cu" "B.Mask" "B.Paste")
			(net "P3V3_STBY")
		)
		(pad "2" smd rect
			(at 0 0.889 180)
			(size 0.508 0.508)
			(layers "B.Cu" "B.Mask" "B.Paste")
			(net "GND")
		)
		(zone
			(layer "B.Cu")
			(hatch none 0.5)
			(connect_pads
				(clearance 0)
			)
			(min_thickness 0.25)
			(keepout
				(tracks allowed)
				(vias not_allowed)
				(pads allowed)
				(copperpour not_allowed)
				(footprints allowed)
			)
			(placement
				(enabled no)
				(sheetname "")
			)
			(fill
				(thermal_gap 0.5)
				(thermal_bridge_width 0.5)
				(island_removal_mode 0)
			)
			(polygon
				(pts
					(xy 461.1116 -126.5174) (xy 460.6036 -126.5174) (xy 460.6036 -126.1364) (xy 461.1116 -126.1364)
				)
			)
		)
		(zone
			(layer "B.Cu")
			(hatch none 0.5)
			(connect_pads
				(clearance 0)
			)
			(min_thickness 0.25)
			(keepout
				(tracks not_allowed)
				(vias allowed)
				(pads allowed)
				(copperpour not_allowed)
				(footprints allowed)
			)
			(placement
				(enabled no)
				(sheetname "")
			)
			(fill
				(thermal_gap 0.5)
				(thermal_bridge_width 0.5)
				(island_removal_mode 0)
			)
			(polygon
				(pts
					(xy 461.1116 -126.1364) (xy 460.6036 -126.1364) (xy 460.6036 -126.5174) (xy 461.1116 -126.5174)
				)
			)
		)
	)
)
